(kicad_pcb
	(version 20241229)
	(generator "pcbnew")
	(generator_version "9.0")
	(general
		(thickness 1.599998)
		(legacy_teardrops no)
	)
	(paper "A4")
	(title_block
		(date "2023-02-12")
		(rev "1.1.5")
		(comment 9 "footprints 429-435 of 473")
	)
	(layers
		(0 "F.Cu" signal)
		(4 "In1.Cu" power "In1.GND")
		(6 "In2.Cu" signal)
		(8 "In3.Cu" power "In3.GND")
		(10 "In4.Cu" power "In4.VCC")
		(12 "In5.Cu" signal)
		(14 "In6.Cu" power "In6.VCC")
		(2 "B.Cu" signal)
		(9 "F.Adhes" user "F.Adhesive")
		(11 "B.Adhes" user "B.Adhesive")
		(13 "F.Paste" user)
		(15 "B.Paste" user)
		(5 "F.SilkS" user "F.Silkscreen")
		(7 "B.SilkS" user "B.Silkscreen")
		(1 "F.Mask" user)
		(3 "B.Mask" user)
		(17 "Dwgs.User" user "User.Drawings")
		(19 "Cmts.User" user "User.Comments")
		(21 "Eco1.User" user "User.Eco1")
		(23 "Eco2.User" user "User.Eco2")
		(25 "Edge.Cuts" user)
		(27 "Margin" user)
		(31 "F.CrtYd" user "F.Courtyard")
		(29 "B.CrtYd" user "B.Courtyard")
		(35 "F.Fab" user)
		(33 "B.Fab" user)
	)
	(footprint "antmicro-footprints:C_0402_1005Metric"
		(layer "B.Cu")
		(at 200.486328 100.020008 -90)
		(descr "Capacitor SMD 0402")
		(tags "capacitor SMD 0402")
		(property "Reference" "C116"
			(at -1.820008 -6.613672 90)
			(layer "B.SilkS")
			(effects
				(font
					(size 0.7 0.7)
					(thickness 0.15)
				)
				(justify left bottom mirror)
			)
		)
		(property "Value" "C_10n_0402"
			(at 0 -1.4 90)
			(layer "B.Fab")
			(effects
				(font
					(size 0.7 0.7)
					(thickness 0.15)
				)
				(justify left bottom mirror)
			)
		)
		(property "Description" " "
			(at 0 0 270)
			(layer "F.Fab")
			(hide yes)
			(effects
				(font
					(size 1.27 1.27)
					(thickness 0.15)
				)
			)
		)
		(property "Author" "Antmicro"
			(at 100.46632 300.506336 0)
			(layer "B.Fab")
			(hide yes)
			(effects
				(font
					(size 1 1)
					(thickness 0.15)
				)
				(justify mirror)
			)
		)
		(property "Dielectric" "X7R"
			(at 100.46632 300.506336 0)
			(layer "B.Fab")
			(hide yes)
			(effects
				(font
					(size 1 1)
					(thickness 0.15)
				)
				(justify mirror)
			)
		)
		(property "License" "Apache-2.0"
			(at 100.46632 300.506336 0)
			(layer "B.Fab")
			(hide yes)
			(effects
				(font
					(size 1 1)
					(thickness 0.15)
				)
				(justify mirror)
			)
		)
		(property "MPN" "GRM155R71H103KA88D"
			(at 100.46632 300.506336 0)
			(layer "B.Fab")
			(hide yes)
			(effects
				(font
					(size 1 1)
					(thickness 0.15)
				)
				(justify mirror)
			)
		)
		(property "Manufacturer" "Murata"
			(at 100.46632 300.506336 0)
			(layer "B.Fab")
			(hide yes)
			(effects
				(font
					(size 1 1)
					(thickness 0.15)
				)
				(justify mirror)
			)
		)
		(property "Val" "10n"
			(at 100.46632 300.506336 0)
			(layer "B.Fab")
			(hide yes)
			(effects
				(font
					(size 1 1)
					(thickness 0.15)
				)
				(justify mirror)
			)
		)
		(property "Voltage" "50V"
			(at 100.46632 300.506336 0)
			(layer "B.Fab")
			(hide yes)
			(effects
				(font
					(size 1 1)
					(thickness 0.15)
				)
				(justify mirror)
			)
		)
		(sheetname "Ethernet")
		(sheetfile "ethernet.kicad_sch")
		(attr smd)
		(fp_rect
			(start -0.94 0.47)
			(end 0.94 -0.47)
			(stroke
				(width 0.05)
				(type solid)
			)
			(fill no)
			(layer "B.CrtYd")
		)
		(fp_rect
			(start -0.499 0.249)
			(end 0.499 -0.249)
			(stroke
				(width 0.15)
				(type solid)
			)
			(fill no)
			(layer "B.Fab")
		)
		(pad "1" smd roundrect
			(at -0.484 0 270)
			(size 0.59 0.64)
			(layers "B.Cu" "B.Mask" "B.Paste")
			(roundrect_rratio 0.25)
			(net 602 "1V2_SYS")
			(pintype "passive")
		)
		(pad "2" smd roundrect
			(at 0.484 0 270)
			(size 0.59 0.64)
			(layers "B.Cu" "B.Mask" "B.Paste")
			(roundrect_rratio 0.25)
			(net 5 "GND")
			(pintype "passive")
		)
	)
	(footprint "antmicro-footprints:C_0402_1005Metric"
		(layer "B.Cu")
		(at 204.186328 108.774306 -90)
		(descr "Capacitor SMD 0402")
		(tags "capacitor SMD 0402")
		(property "Reference" "C118"
			(at 0.810694 -0.413672 90)
			(layer "B.SilkS")
			(effects
				(font
					(size 0.7 0.7)
					(thickness 0.15)
				)
				(justify left bottom mirror)
			)
		)
		(property "Value" "C_4u7_0402"
			(at 0 -1.4 90)
			(layer "B.Fab")
			(effects
				(font
					(size 0.7 0.7)
					(thickness 0.15)
				)
				(justify left bottom mirror)
			)
		)
		(property "Description" " "
			(at 0 0 270)
			(layer "F.Fab")
			(hide yes)
			(effects
				(font
					(size 1.27 1.27)
					(thickness 0.15)
				)
			)
		)
		(property "Author" "Antmicro"
			(at 95.412022 312.960634 0)
			(layer "B.Fab")
			(hide yes)
			(effects
				(font
					(size 1 1)
					(thickness 0.15)
				)
				(justify mirror)
			)
		)
		(property "Dielectric" ""
			(at 95.412022 312.960634 0)
			(layer "B.Fab")
			(hide yes)
			(effects
				(font
					(size 1 1)
					(thickness 0.15)
				)
				(justify mirror)
			)
		)
		(property "License" "Apache-2.0"
			(at 95.412022 312.960634 0)
			(layer "B.Fab")
			(hide yes)
			(effects
				(font
					(size 1 1)
					(thickness 0.15)
				)
				(justify mirror)
			)
		)
		(property "MPN" "GRM155R61A475MEAAD"
			(at 95.412022 312.960634 0)
			(layer "B.Fab")
			(hide yes)
			(effects
				(font
					(size 1 1)
					(thickness 0.15)
				)
				(justify mirror)
			)
		)
		(property "Manufacturer" "Murata"
			(at 95.412022 312.960634 0)
			(layer "B.Fab")
			(hide yes)
			(effects
				(font
					(size 1 1)
					(thickness 0.15)
				)
				(justify mirror)
			)
		)
		(property "Val" "4u7"
			(at 95.412022 312.960634 0)
			(layer "B.Fab")
			(hide yes)
			(effects
				(font
					(size 1 1)
					(thickness 0.15)
				)
				(justify mirror)
			)
		)
		(property "Voltage" ""
			(at 95.412022 312.960634 0)
			(layer "B.Fab")
			(hide yes)
			(effects
				(font
					(size 1 1)
					(thickness 0.15)
				)
				(justify mirror)
			)
		)
		(sheetname "Ethernet")
		(sheetfile "ethernet.kicad_sch")
		(attr smd)
		(fp_rect
			(start -0.94 0.47)
			(end 0.94 -0.47)
			(stroke
				(width 0.05)
				(type solid)
			)
			(fill no)
			(layer "B.CrtYd")
		)
		(fp_rect
			(start -0.499 0.249)
			(end 0.499 -0.249)
			(stroke
				(width 0.15)
				(type solid)
			)
			(fill no)
			(layer "B.Fab")
		)
		(pad "1" smd roundrect
			(at -0.484 0 270)
			(size 0.59 0.64)
			(layers "B.Cu" "B.Mask" "B.Paste")
			(roundrect_rratio 0.25)
			(net 531 "/Ethernet/AVDDH")
			(pintype "passive")
		)
		(pad "2" smd roundrect
			(at 0.484 0 270)
			(size 0.59 0.64)
			(layers "B.Cu" "B.Mask" "B.Paste")
			(roundrect_rratio 0.25)
			(net 5 "GND")
			(pintype "passive")
		)
	)
	(footprint "antmicro-footprints:C_0402_1005Metric"
		(layer "B.Cu")
		(at 202.686328 100.020008 -90)
		(descr "Capacitor SMD 0402")
		(tags "capacitor SMD 0402")
		(property "Reference" "C119"
			(at -1.820008 -6.613672 90)
			(layer "B.SilkS")
			(effects
				(font
					(size 0.7 0.7)
					(thickness 0.15)
				)
				(justify left bottom mirror)
			)
		)
		(property "Value" "C_10n_0402"
			(at 0 -1.4 90)
			(layer "B.Fab")
			(effects
				(font
					(size 0.7 0.7)
					(thickness 0.15)
				)
				(justify left bottom mirror)
			)
		)
		(property "Description" " "
			(at 0 0 270)
			(layer "F.Fab")
			(hide yes)
			(effects
				(font
					(size 1.27 1.27)
					(thickness 0.15)
				)
			)
		)
		(property "Author" "Antmicro"
			(at 102.66632 302.706336 0)
			(layer "B.Fab")
			(hide yes)
			(effects
				(font
					(size 1 1)
					(thickness 0.15)
				)
				(justify mirror)
			)
		)
		(property "Dielectric" "X7R"
			(at 102.66632 302.706336 0)
			(layer "B.Fab")
			(hide yes)
			(effects
				(font
					(size 1 1)
					(thickness 0.15)
				)
				(justify mirror)
			)
		)
		(property "License" "Apache-2.0"
			(at 102.66632 302.706336 0)
			(layer "B.Fab")
			(hide yes)
			(effects
				(font
					(size 1 1)
					(thickness 0.15)
				)
				(justify mirror)
			)
		)
		(property "MPN" "GRM155R71H103KA88D"
			(at 102.66632 302.706336 0)
			(layer "B.Fab")
			(hide yes)
			(effects
				(font
					(size 1 1)
					(thickness 0.15)
				)
				(justify mirror)
			)
		)
		(property "Manufacturer" "Murata"
			(at 102.66632 302.706336 0)
			(layer "B.Fab")
			(hide yes)
			(effects
				(font
					(size 1 1)
					(thickness 0.15)
				)
				(justify mirror)
			)
		)
		(property "Val" "10n"
			(at 102.66632 302.706336 0)
			(layer "B.Fab")
			(hide yes)
			(effects
				(font
					(size 1 1)
					(thickness 0.15)
				)
				(justify mirror)
			)
		)
		(property "Voltage" "50V"
			(at 102.66632 302.706336 0)
			(layer "B.Fab")
			(hide yes)
			(effects
				(font
					(size 1 1)
					(thickness 0.15)
				)
				(justify mirror)
			)
		)
		(sheetname "Ethernet")
		(sheetfile "ethernet.kicad_sch")
		(attr smd)
		(fp_rect
			(start -0.94 0.47)
			(end 0.94 -0.47)
			(stroke
				(width 0.05)
				(type solid)
			)
			(fill no)
			(layer "B.CrtYd")
		)
		(fp_rect
			(start -0.499 0.249)
			(end 0.499 -0.249)
			(stroke
				(width 0.15)
				(type solid)
			)
			(fill no)
			(layer "B.Fab")
		)
		(pad "1" smd roundrect
			(at -0.484 0 270)
			(size 0.59 0.64)
			(layers "B.Cu" "B.Mask" "B.Paste")
			(roundrect_rratio 0.25)
			(net 602 "1V2_SYS")
			(pintype "passive")
		)
		(pad "2" smd roundrect
			(at 0.484 0 270)
			(size 0.59 0.64)
			(layers "B.Cu" "B.Mask" "B.Paste")
			(roundrect_rratio 0.25)
			(net 5 "GND")
			(pintype "passive")
		)
	)
	(footprint "antmicro-footprints:FB_0603_1608Metric"
		(layer "B.Cu")
		(at 195.786328 108.274306)
		(property "Reference" "FB4"
			(at 1.113672 1.525694 180)
			(layer "B.SilkS")
			(effects
				(font
					(size 0.7 0.7)
					(thickness 0.15)
				)
				(justify left bottom mirror)
			)
		)
		(property "Value" "FB_120Z_2A_0603"
			(at 0 -1.5 180)
			(layer "B.Fab")
			(effects
				(font
					(size 0.7 0.7)
					(thickness 0.15)
				)
				(justify left bottom mirror)
			)
		)
		(property "Description" "Ferrite Beads WE-TMSB Suppression 240Ohm 200mA "
			(at 0 0 0)
			(layer "F.Fab")
			(hide yes)
			(effects
				(font
					(size 1.27 1.27)
					(thickness 0.15)
				)
			)
		)
		(property "Author" "Antmicro"
			(at 0 0 0)
			(layer "B.Fab")
			(hide yes)
			(effects
				(font
					(size 1 1)
					(thickness 0.15)
				)
				(justify mirror)
			)
		)
		(property "License" "Apache-2.0"
			(at 0 0 0)
			(layer "B.Fab")
			(hide yes)
			(effects
				(font
					(size 1 1)
					(thickness 0.15)
				)
				(justify mirror)
			)
		)
		(property "MPN" "BLM18PG121SN1D"
			(at 0 0 0)
			(layer "B.Fab")
			(hide yes)
			(effects
				(font
					(size 1 1)
					(thickness 0.15)
				)
				(justify mirror)
			)
		)
		(property "Manufacturer" "Murata"
			(at 0 0 0)
			(layer "B.Fab")
			(hide yes)
			(effects
				(font
					(size 1 1)
					(thickness 0.15)
				)
				(justify mirror)
			)
		)
		(sheetname "Ethernet")
		(sheetfile "ethernet.kicad_sch")
		(attr smd)
		(fp_line
			(start -0.196 -0.406)
			(end 0.193 -0.406)
			(stroke
				(width 0.15)
				(type solid)
			)
			(layer "B.SilkS")
		)
		(fp_line
			(start -0.196 0.408)
			(end 0.193 0.408)
			(stroke
				(width 0.15)
				(type solid)
			)
			(layer "B.SilkS")
		)
		(fp_rect
			(start -1.3 0.6)
			(end 1.3 -0.6)
			(stroke
				(width 0.05)
				(type solid)
			)
			(fill no)
			(layer "B.CrtYd")
		)
		(fp_line
			(start -0.803 -0.406)
			(end -0.803 0.408)
			(stroke
				(width 0.15)
				(type solid)
			)
			(layer "B.Fab")
		)
		(fp_line
			(start 0.8 -0.406)
			(end -0.803 -0.406)
			(stroke
				(width 0.15)
				(type solid)
			)
			(layer "B.Fab")
		)
		(fp_line
			(start 0.8 0.408)
			(end -0.803 0.408)
			(stroke
				(width 0.15)
				(type solid)
			)
			(layer "B.Fab")
		)
		(fp_line
			(start 0.8 0.408)
			(end 0.8 -0.406)
			(stroke
				(width 0.15)
				(type solid)
			)
			(layer "B.Fab")
		)
		(pad "1" smd roundrect
			(at -0.891 0)
			(size 0.762 1.09)
			(layers "B.Cu" "B.Mask" "B.Paste")
			(roundrect_rratio 0.15)
			(net 459 "3V3_SYS")
			(pintype "passive")
		)
		(pad "2" smd roundrect
			(at 0.888 0)
			(size 0.762 1.09)
			(layers "B.Cu" "B.Mask" "B.Paste")
			(roundrect_rratio 0.15)
			(net 531 "/Ethernet/AVDDH")
			(pintype "passive")
		)
	)
	(footprint "antmicro-footprints:FB_0603_1608Metric"
		(layer "B.Cu")
		(at 213.086328 121.189063 90)
		(property "Reference" "FB7"
			(at 0.989063 1.513672 270)
			(layer "B.SilkS")
			(effects
				(font
					(size 0.7 0.7)
					(thickness 0.15)
				)
				(justify left bottom mirror)
			)
		)
		(property "Value" "FB_120Z_2A_0603"
			(at 0 -1.5 270)
			(layer "B.Fab")
			(effects
				(font
					(size 0.7 0.7)
					(thickness 0.15)
				)
				(justify left bottom mirror)
			)
		)
		(property "Description" "Ferrite Beads WE-TMSB Suppression 240Ohm 200mA "
			(at 0 0 90)
			(layer "F.Fab")
			(hide yes)
			(effects
				(font
					(size 1.27 1.27)
					(thickness 0.15)
				)
			)
		)
		(property "Author" "Antmicro"
			(at 334.275391 -91.897265 0)
			(layer "B.Fab")
			(hide yes)
			(effects
				(font
					(size 1 1)
					(thickness 0.15)
				)
				(justify mirror)
			)
		)
		(property "License" "Apache-2.0"
			(at 334.275391 -91.897265 0)
			(layer "B.Fab")
			(hide yes)
			(effects
				(font
					(size 1 1)
					(thickness 0.15)
				)
				(justify mirror)
			)
		)
		(property "MPN" "BLM18PG121SN1D"
			(at 334.275391 -91.897265 0)
			(layer "B.Fab")
			(hide yes)
			(effects
				(font
					(size 1 1)
					(thickness 0.15)
				)
				(justify mirror)
			)
		)
		(property "Manufacturer" "Murata"
			(at 334.275391 -91.897265 0)
			(layer "B.Fab")
			(hide yes)
			(effects
				(font
					(size 1 1)
					(thickness 0.15)
				)
				(justify mirror)
			)
		)
		(sheetname "Ethernet")
		(sheetfile "ethernet.kicad_sch")
		(attr smd)
		(fp_line
			(start -0.196 -0.406)
			(end 0.193 -0.406)
			(stroke
				(width 0.15)
				(type solid)
			)
			(layer "B.SilkS")
		)
		(fp_line
			(start -0.196 0.408)
			(end 0.193 0.408)
			(stroke
				(width 0.15)
				(type solid)
			)
			(layer "B.SilkS")
		)
		(fp_rect
			(start -1.3 0.6)
			(end 1.3 -0.6)
			(stroke
				(width 0.05)
				(type solid)
			)
			(fill no)
			(layer "B.CrtYd")
		)
		(fp_line
			(start 0.8 -0.406)
			(end -0.803 -0.406)
			(stroke
				(width 0.15)
				(type solid)
			)
			(layer "B.Fab")
		)
		(fp_line
			(start -0.803 -0.406)
			(end -0.803 0.408)
			(stroke
				(width 0.15)
				(type solid)
			)
			(layer "B.Fab")
		)
		(fp_line
			(start 0.8 0.408)
			(end 0.8 -0.406)
			(stroke
				(width 0.15)
				(type solid)
			)
			(layer "B.Fab")
		)
		(fp_line
			(start 0.8 0.408)
			(end -0.803 0.408)
			(stroke
				(width 0.15)
				(type solid)
			)
			(layer "B.Fab")
		)
		(pad "1" smd roundrect
			(at -0.891 0 90)
			(size 0.762 1.09)
			(layers "B.Cu" "B.Mask" "B.Paste")
			(roundrect_rratio 0.15)
			(net 521 "Net-(FB7-Pad1)")
			(pintype "passive")
		)
		(pad "2" smd roundrect
			(at 0.888 0 90)
			(size 0.762 1.09)
			(layers "B.Cu" "B.Mask" "B.Paste")
			(roundrect_rratio 0.15)
			(net 5 "GND")
			(pintype "passive")
		)
	)
	(footprint "antmicro-footprints:R_0402_1005Metric"
		(layer "B.Cu")
		(at 191.686328 128.989063 180)
		(descr "Resistor SMD 0402")
		(tags "resistor SMD 0402")
		(property "Reference" "R70"
			(at -1.013672 0.489063 0)
			(layer "B.SilkS")
			(effects
				(font
					(size 0.7 0.7)
					(thickness 0.15)
				)
				(justify left bottom mirror)
			)
		)
		(property "Value" "R_220R_0402"
			(at 0 -1.4 0)
			(layer "B.Fab")
			(effects
				(font
					(size 0.7 0.7)
					(thickness 0.15)
				)
				(justify left bottom mirror)
			)
		)
		(property "Description" "220R resistor in 0402 package with 1% tolerance"
			(at 0 0 180)
			(layer "F.Fab")
			(hide yes)
			(effects
				(font
					(size 1.27 1.27)
					(thickness 0.15)
				)
			)
		)
		(property "Author" "Antmicro"
			(at 383.372656 257.978126 0)
			(layer "B.Fab")
			(hide yes)
			(effects
				(font
					(size 1 1)
					(thickness 0.15)
				)
				(justify mirror)
			)
		)
		(property "License" "Apache-2.0"
			(at 383.372656 257.978126 0)
			(layer "B.Fab")
			(hide yes)
			(effects
				(font
					(size 1 1)
					(thickness 0.15)
				)
				(justify mirror)
			)
		)
		(property "MPN" "CR0402-FX-2200GLF"
			(at 383.372656 257.978126 0)
			(layer "B.Fab")
			(hide yes)
			(effects
				(font
					(size 1 1)
					(thickness 0.15)
				)
				(justify mirror)
			)
		)
		(property "Manufacturer" "Bourns"
			(at 383.372656 257.978126 0)
			(layer "B.Fab")
			(hide yes)
			(effects
				(font
					(size 1 1)
					(thickness 0.15)
				)
				(justify mirror)
			)
		)
		(property "Tolerance" "1%"
			(at 383.372656 257.978126 0)
			(layer "B.Fab")
			(hide yes)
			(effects
				(font
					(size 1 1)
					(thickness 0.15)
				)
				(justify mirror)
			)
		)
		(property "Val" "220R"
			(at 383.372656 257.978126 0)
			(layer "B.Fab")
			(hide yes)
			(effects
				(font
					(size 1 1)
					(thickness 0.15)
				)
				(justify mirror)
			)
		)
		(sheetname "Ethernet")
		(sheetfile "ethernet.kicad_sch")
		(attr smd)
		(fp_rect
			(start -0.93 0.47)
			(end 0.93 -0.47)
			(stroke
				(width 0.05)
				(type solid)
			)
			(fill no)
			(layer "B.CrtYd")
		)
		(fp_rect
			(start -0.5 0.25)
			(end 0.5 -0.25)
			(stroke
				(width 0.15)
				(type solid)
			)
			(fill no)
			(layer "B.Fab")
		)
		(pad "1" smd roundrect
			(at -0.485 0 180)
			(size 0.59 0.64)
			(layers "B.Cu" "B.Mask" "B.Paste")
			(roundrect_rratio 0.25)
			(net 89 "Net-(J5-LED1_Y+)")
			(pintype "passive")
		)
		(pad "2" smd roundrect
			(at 0.485 0 180)
			(size 0.59 0.64)
			(layers "B.Cu" "B.Mask" "B.Paste")
			(roundrect_rratio 0.25)
			(net 459 "3V3_SYS")
			(pintype "passive")
		)
	)
	(footprint "antmicro-footprints:R_0402_1005Metric"
		(layer "B.Cu")
		(at 202.686328 128.989063 180)
		(descr "Resistor SMD 0402")
		(tags "resistor SMD 0402")
		(property "Reference" "R71"
			(at -1.013672 0.489063 0)
			(layer "B.SilkS")
			(effects
				(font
					(size 0.7 0.7)
					(thickness 0.15)
				)
				(justify left bottom mirror)
			)
		)
		(property "Value" "R_220R_0402"
			(at 0 -1.4 0)
			(layer "B.Fab")
			(effects
				(font
					(size 0.7 0.7)
					(thickness 0.15)
				)
				(justify left bottom mirror)
			)
		)
		(property "Description" "220R resistor in 0402 package with 1% tolerance"
			(at 0 0 180)
			(layer "F.Fab")
			(hide yes)
			(effects
				(font
					(size 1.27 1.27)
					(thickness 0.15)
				)
			)
		)
		(property "Author" "Antmicro"
			(at 405.372656 257.978126 0)
			(layer "B.Fab")
			(hide yes)
			(effects
				(font
					(size 1 1)
					(thickness 0.15)
				)
				(justify mirror)
			)
		)
		(property "License" "Apache-2.0"
			(at 405.372656 257.978126 0)
			(layer "B.Fab")
			(hide yes)
			(effects
				(font
					(size 1 1)
					(thickness 0.15)
				)
				(justify mirror)
			)
		)
		(property "MPN" "CR0402-FX-2200GLF"
			(at 405.372656 257.978126 0)
			(layer "B.Fab")
			(hide yes)
			(effects
				(font
					(size 1 1)
					(thickness 0.15)
				)
				(justify mirror)
			)
		)
		(property "Manufacturer" "Bourns"
			(at 405.372656 257.978126 0)
			(layer "B.Fab")
			(hide yes)
			(effects
				(font
					(size 1 1)
					(thickness 0.15)
				)
				(justify mirror)
			)
		)
		(property "Tolerance" "1%"
			(at 405.372656 257.978126 0)
			(layer "B.Fab")
			(hide yes)
			(effects
				(font
					(size 1 1)
					(thickness 0.15)
				)
				(justify mirror)
			)
		)
		(property "Val" "220R"
			(at 405.372656 257.978126 0)
			(layer "B.Fab")
			(hide yes)
			(effects
				(font
					(size 1 1)
					(thickness 0.15)
				)
				(justify mirror)
			)
		)
		(sheetname "Ethernet")
		(sheetfile "ethernet.kicad_sch")
		(attr smd)
		(fp_rect
			(start -0.93 0.47)
			(end 0.93 -0.47)
			(stroke
				(width 0.05)
				(type solid)
			)
			(fill no)
			(layer "B.CrtYd")
		)
		(fp_rect
			(start -0.5 0.25)
			(end 0.5 -0.25)
			(stroke
				(width 0.15)
				(type solid)
			)
			(fill no)
			(layer "B.Fab")
		)
		(pad "1" smd roundrect
			(at -0.485 0 180)
			(size 0.59 0.64)
			(layers "B.Cu" "B.Mask" "B.Paste")
			(roundrect_rratio 0.25)
			(net 90 "Net-(J5-LED2_G+)")
			(pintype "passive")
		)
		(pad "2" smd roundrect
			(at 0.485 0 180)
			(size 0.59 0.64)
			(layers "B.Cu" "B.Mask" "B.Paste")
			(roundrect_rratio 0.25)
			(net 459 "3V3_SYS")
			(pintype "passive")
		)
	)
)
